# T6G (Grand Teton) — schematic netlist excerpt (pin names and nets, part order shuffled) for the footprints in the layout excerpt that follows; sources: Cadence DE-HDL packaged netlist, KiCad conversion of 04192023_DAF0TMB3IC0_F0TG_MB_C_brd_V02_OCP.brd

R1171  Q_RES  1K 1% CHIP  pkg 0402LF  page 142 : A = P3V3_AUX ; B = OCP_V3_2_P3V3_PLD_R_PWRGD
R1727  Q_RES  10K 1% EMPTY  pkg 0402LF  page 171 : A = P3V3_AUX ; B = JTAG_SCM_TDO
C1569  Q_CAP_DIFFBUS  DIFF BUS_0.22UF 6.3V 20% X6S  pkg C0201  page 65 : \1\ = P5E_CPU0_G3_TX_C_DP<5> ; \2\ = P5E_CPU0_G3_TX_DP<5>

(kicad_pcb
	(version 20260206)
	(generator "pcbnew")
	(generator_version "10.0")
	(general
		(thickness 1.6)
		(legacy_teardrops no)
	)
	(paper "A4")
	(title_block
		(title "04192023_DAF0TMB3IC0_F0TG_MB_C_brd_V02_OCP.brd")
		(comment 1 "Grand Teton / footprints 4130-4132 of 8354")
	)
	(layers
		(0 "F.Cu" signal "TOP")
		(4 "In1.Cu" signal "GND")
		(6 "In2.Cu" signal "IN1")
		(8 "In3.Cu" signal "GND1")
		(10 "In4.Cu" signal "IN2")
		(12 "In5.Cu" signal "GND2")
		(14 "In6.Cu" signal "IN3")
		(16 "In7.Cu" signal "GND3")
		(18 "In8.Cu" signal "VCC")
		(20 "In9.Cu" signal "VCC1")
		(22 "In10.Cu" signal "GND4")
		(24 "In11.Cu" signal "IN4")
		(26 "In12.Cu" signal "GND5")
		(28 "In13.Cu" signal "IN5")
		(30 "In14.Cu" signal "GND6")
		(32 "In15.Cu" signal "IN6")
		(34 "In16.Cu" signal "GND7")
		(2 "B.Cu" signal "BOTTOM")
		(9 "F.Adhes" user "F.Adhesive")
		(11 "B.Adhes" user "B.Adhesive")
		(13 "F.Paste" user "Package Geometry/Pastemask Top")
		(15 "B.Paste" user "Package Geometry/Pastemask Bottom")
		(5 "F.SilkS" user "Ref Des/Silkscreen Top")
		(7 "B.SilkS" user "Ref Des/Silkscreen Bottom")
		(1 "F.Mask" user "Board Geometry/Soldermask Top")
		(3 "B.Mask" user "Board Geometry/Soldermask Bottom")
		(17 "Dwgs.User" user "User.Drawings")
		(19 "Cmts.User" user "User.Comments")
		(21 "Eco1.User" user "User.Eco1")
		(23 "Eco2.User" user "User.Eco2")
		(25 "Edge.Cuts" user "Board Geometry/Outline")
		(27 "Margin" user)
		(31 "F.CrtYd" user "Package Geometry/Place Bound Top")
		(29 "B.CrtYd" user "Package Geometry/Place Bound Bottom")
		(35 "F.Fab" user "Ref Des/Assembly Top")
		(33 "B.Fab" user "Ref Des/Assembly Bottom")
	)
	(footprint ""
		(layer "F.Cu")
		(at 125.992636 -60.482226)
		(property "Reference" "R1727"
			(at 0 0 0)
			(layer "F.SilkS")
			(hide yes)
			(effects
				(font
					(size 1.27 1.27)
				)
			)
		)
		(property "Value" ""
			(at 0 0 0)
			(layer "F.Fab")
			(effects
				(font
					(size 1.27 1.27)
				)
			)
		)
		(duplicate_pad_numbers_are_jumpers no)
		(fp_line
			(start -0.7874 -0.4064)
			(end 0.7874 -0.4064)
			(stroke
				(width 0.1524)
				(type default)
			)
			(layer "F.SilkS")
		)
		(fp_line
			(start -0.7874 0.4064)
			(end -0.7874 -0.4064)
			(stroke
				(width 0.1524)
				(type default)
			)
			(layer "F.SilkS")
		)
		(fp_line
			(start 0.7874 -0.4064)
			(end 0.7874 0.4064)
			(stroke
				(width 0.1524)
				(type default)
			)
			(layer "F.SilkS")
		)
		(fp_line
			(start 0.7874 0.4064)
			(end -0.7874 0.4064)
			(stroke
				(width 0.1524)
				(type default)
			)
			(layer "F.SilkS")
		)
		(fp_line
			(start -0.67945 -0.305054)
			(end -0.12065 -0.305054)
			(stroke
				(width 0.1)
				(type default)
			)
			(layer "F.Fab")
		)
		(fp_line
			(start -0.67945 0.3048)
			(end -0.67945 -0.305054)
			(stroke
				(width 0.1)
				(type default)
			)
			(layer "F.Fab")
		)
		(fp_line
			(start -0.12065 -0.305054)
			(end -0.12065 -0.2794)
			(stroke
				(width 0.1)
				(type default)
			)
			(layer "F.Fab")
		)
		(fp_line
			(start -0.12065 -0.2794)
			(end 0.12065 -0.2794)
			(stroke
				(width 0.1)
				(type default)
			)
			(layer "F.Fab")
		)
		(fp_line
			(start -0.12065 0.2794)
			(end -0.12065 0.3048)
			(stroke
				(width 0.1)
				(type default)
			)
			(layer "F.Fab")
		)
		(fp_line
			(start -0.12065 0.3048)
			(end -0.67945 0.3048)
			(stroke
				(width 0.1)
				(type default)
			)
			(layer "F.Fab")
		)
		(fp_line
			(start 0.120396 0.2794)
			(end -0.12065 0.2794)
			(stroke
				(width 0.1)
				(type default)
			)
			(layer "F.Fab")
		)
		(fp_line
			(start 0.120396 0.3048)
			(end 0.120396 0.2794)
			(stroke
				(width 0.1)
				(type default)
			)
			(layer "F.Fab")
		)
		(fp_line
			(start 0.12065 -0.3048)
			(end 0.67945 -0.3048)
			(stroke
				(width 0.1)
				(type default)
			)
			(layer "F.Fab")
		)
		(fp_line
			(start 0.12065 -0.2794)
			(end 0.12065 -0.3048)
			(stroke
				(width 0.1)
				(type default)
			)
			(layer "F.Fab")
		)
		(fp_line
			(start 0.67945 -0.3048)
			(end 0.67945 0.3048)
			(stroke
				(width 0.1)
				(type default)
			)
			(layer "F.Fab")
		)
		(fp_line
			(start 0.67945 0.3048)
			(end 0.120396 0.3048)
			(stroke
				(width 0.1)
				(type default)
			)
			(layer "F.Fab")
		)
		(pad "1" smd circle
			(at -0.40005 0)
			(size 0 0)
			(layers "F.Cu" "F.Mask" "F.Paste")
			(net "P3V3_AUX")
		)
		(pad "2" smd circle
			(at 0.40005 0)
			(size 0 0)
			(layers "F.Cu" "F.Mask" "F.Paste")
			(net "JTAG_SCM_TDO")
		)
	)
	(footprint ""
		(layer "F.Cu")
		(at 86.868 -70.866 -90)
		(property "Reference" "R1171"
			(at 0 0 270)
			(layer "F.SilkS")
			(hide yes)
			(effects
				(font
					(size 1.27 1.27)
				)
			)
		)
		(property "Value" ""
			(at 0 0 270)
			(layer "F.Fab")
			(effects
				(font
					(size 1.27 1.27)
				)
			)
		)
		(duplicate_pad_numbers_are_jumpers no)
		(fp_line
			(start -0.7874 0.4064)
			(end -0.7874 -0.4064)
			(stroke
				(width 0.1524)
				(type default)
			)
			(layer "F.SilkS")
		)
		(fp_line
			(start 0.7874 0.4064)
			(end -0.7874 0.4064)
			(stroke
				(width 0.1524)
				(type default)
			)
			(layer "F.SilkS")
		)
		(fp_line
			(start -0.7874 -0.4064)
			(end 0.7874 -0.4064)
			(stroke
				(width 0.1524)
				(type default)
			)
			(layer "F.SilkS")
		)
		(fp_line
			(start 0.7874 -0.4064)
			(end 0.7874 0.4064)
			(stroke
				(width 0.1524)
				(type default)
			)
			(layer "F.SilkS")
		)
		(fp_line
			(start -0.67945 0.3048)
			(end -0.67945 -0.305054)
			(stroke
				(width 0.1)
				(type default)
			)
			(layer "F.Fab")
		)
		(fp_line
			(start -0.12065 0.3048)
			(end -0.67945 0.3048)
			(stroke
				(width 0.1)
				(type default)
			)
			(layer "F.Fab")
		)
		(fp_line
			(start 0.120396 0.3048)
			(end 0.120396 0.2794)
			(stroke
				(width 0.1)
				(type default)
			)
			(layer "F.Fab")
		)
		(fp_line
			(start 0.67945 0.3048)
			(end 0.120396 0.3048)
			(stroke
				(width 0.1)
				(type default)
			)
			(layer "F.Fab")
		)
		(fp_line
			(start -0.12065 0.2794)
			(end -0.12065 0.3048)
			(stroke
				(width 0.1)
				(type default)
			)
			(layer "F.Fab")
		)
		(fp_line
			(start 0.120396 0.2794)
			(end -0.12065 0.2794)
			(stroke
				(width 0.1)
				(type default)
			)
			(layer "F.Fab")
		)
		(fp_line
			(start -0.12065 -0.2794)
			(end 0.12065 -0.2794)
			(stroke
				(width 0.1)
				(type default)
			)
			(layer "F.Fab")
		)
		(fp_line
			(start 0.12065 -0.2794)
			(end 0.12065 -0.3048)
			(stroke
				(width 0.1)
				(type default)
			)
			(layer "F.Fab")
		)
		(fp_line
			(start 0.12065 -0.3048)
			(end 0.67945 -0.3048)
			(stroke
				(width 0.1)
				(type default)
			)
			(layer "F.Fab")
		)
		(fp_line
			(start 0.67945 -0.3048)
			(end 0.67945 0.3048)
			(stroke
				(width 0.1)
				(type default)
			)
			(layer "F.Fab")
		)
		(fp_line
			(start -0.67945 -0.305054)
			(end -0.12065 -0.305054)
			(stroke
				(width 0.1)
				(type default)
			)
			(layer "F.Fab")
		)
		(fp_line
			(start -0.12065 -0.305054)
			(end -0.12065 -0.2794)
			(stroke
				(width 0.1)
				(type default)
			)
			(layer "F.Fab")
		)
		(pad "1" smd circle
			(at -0.40005 0 270)
			(size 0 0)
			(layers "F.Cu" "F.Mask" "F.Paste")
			(net "P3V3_AUX")
		)
		(pad "2" smd circle
			(at 0.40005 0 270)
			(size 0 0)
			(layers "F.Cu" "F.Mask" "F.Paste")
			(net "OCP_V3_2_P3V3_PLD_R_PWRGD")
		)
	)
	(footprint ""
		(layer "F.Cu")
		(at 419.167564 -16.100298 90)
		(property "Reference" "C1569"
			(at 0 0 90)
			(layer "F.SilkS")
			(hide yes)
			(effects
				(font
					(size 1.27 1.27)
				)
			)
		)
		(property "Value" ""
			(at 0 0 90)
			(layer "F.Fab")
			(effects
				(font
					(size 1.27 1.27)
				)
			)
		)
		(duplicate_pad_numbers_are_jumpers no)
		(fp_line
			(start 0.299974 -0.150114)
			(end 0.299974 0.150114)
			(stroke
				(width 0.1)
				(type default)
			)
			(layer "F.Fab")
		)
		(fp_line
			(start -0.299974 -0.150114)
			(end 0.299974 -0.150114)
			(stroke
				(width 0.1)
				(type default)
			)
			(layer "F.Fab")
		)
		(fp_line
			(start 0.299974 0.150114)
			(end -0.299974 0.150114)
			(stroke
				(width 0.1)
				(type default)
			)
			(layer "F.Fab")
		)
		(fp_line
			(start -0.299974 0.150114)
			(end -0.299974 -0.150114)
			(stroke
				(width 0.1)
				(type default)
			)
			(layer "F.Fab")
		)
		(pad "1" smd rect
			(at -0.2667 0 90)
			(size 0.3048 0.381)
			(layers "F.Cu" "F.Mask" "F.Paste")
			(net "P5E_CPU0_G3_TX_C_DP<5>")
		)
		(pad "2" smd rect
			(at 0.2667 0 90)
			(size 0.3048 0.381)
			(layers "F.Cu" "F.Mask" "F.Paste")
			(net "P5E_CPU0_G3_TX_DP<5>")
		)
	)
)
